(kicad_pcb
	(version 20260206)
	(generator "pcbnew")
	(generator_version "10.0")
	(general
		(thickness 1.6)
		(legacy_teardrops no)
	)
	(paper "A4")
	(title_block
		(title "Wiwynn_Tioga_Pass_MB.brd")
		(comment 1 "Tioga Pass / footprints 3537-3543 of 4770")
	)
	(layers
		(0 "F.Cu" signal "TOP")
		(4 "In1.Cu" signal "L2GND")
		(6 "In2.Cu" signal "L3")
		(8 "In3.Cu" signal "L4GND")
		(10 "In4.Cu" signal "L5")
		(12 "In5.Cu" signal "L6GND")
		(14 "In6.Cu" signal "L7VCC")
		(16 "In7.Cu" signal "L8VCC")
		(18 "In8.Cu" signal "L9GND")
		(20 "In9.Cu" signal "L10")
		(22 "In10.Cu" signal "L11GND")
		(24 "In11.Cu" signal "L12")
		(26 "In12.Cu" signal "L13GND")
		(2 "B.Cu" signal "BOTTOM")
		(9 "F.Adhes" user "F.Adhesive")
		(11 "B.Adhes" user "B.Adhesive")
		(13 "F.Paste" user "Package Geometry/Pastemask Top")
		(15 "B.Paste" user "Package Geometry/Pastemask Bottom")
		(5 "F.SilkS" user "Ref Des/Silkscreen Top")
		(7 "B.SilkS" user "Ref Des/Silkscreen Bottom")
		(1 "F.Mask" user "Board Geometry/Soldermask Top")
		(3 "B.Mask" user "Board Geometry/Soldermask Bottom")
		(17 "Dwgs.User" user "User.Drawings")
		(19 "Cmts.User" user "User.Comments")
		(21 "Eco1.User" user "User.Eco1")
		(23 "Eco2.User" user "User.Eco2")
		(25 "Edge.Cuts" user "Board Geometry/Outline")
		(27 "Margin" user)
		(31 "F.CrtYd" user "Package Geometry/Place Bound Top")
		(29 "B.CrtYd" user "Package Geometry/Place Bound Bottom")
		(35 "F.Fab" user "Ref Des/Assembly Top")
		(33 "B.Fab" user "Ref Des/Assembly Bottom")
	)
	(footprint ""
		(layer "B.Cu")
		(at 373.888 -66.929)
		(property "Reference" "R2R6"
			(at 0 0 0)
			(layer "B.SilkS")
			(hide yes)
			(effects
				(font
					(size 1.27 1.27)
				)
				(justify mirror)
			)
		)
		(property "Value" ""
			(at 0 0 0)
			(layer "B.Fab")
			(effects
				(font
					(size 1.27 1.27)
				)
				(justify mirror)
			)
		)
		(duplicate_pad_numbers_are_jumpers no)
		(fp_poly
			(pts
				(xy 0.2794 -0.1016) (xy -0.2794 -0.1016) (xy -0.2794 0.9906) (xy 0.2794 0.9906)
			)
			(stroke
				(width 0)
				(type default)
			)
			(fill no)
			(layer "B.CrtYd")
		)
		(fp_line
			(start -0.2794 -0.1016)
			(end 0.2794 -0.1016)
			(stroke
				(width 0.1)
				(type default)
			)
			(layer "B.Fab")
		)
		(fp_line
			(start -0.2794 0.9906)
			(end -0.2794 -0.1016)
			(stroke
				(width 0.1)
				(type default)
			)
			(layer "B.Fab")
		)
		(fp_line
			(start 0.2794 -0.1016)
			(end 0.2794 0.9906)
			(stroke
				(width 0.1)
				(type default)
			)
			(layer "B.Fab")
		)
		(fp_line
			(start 0.2794 0.9906)
			(end -0.2794 0.9906)
			(stroke
				(width 0.1)
				(type default)
			)
			(layer "B.Fab")
		)
		(pad "1" smd rect
			(at 0 0 180)
			(size 0.508 0.508)
			(layers "B.Cu" "B.Mask" "B.Paste")
			(net "SGPIO_BMC_DIN_R")
		)
		(pad "2" smd rect
			(at 0 0.889 180)
			(size 0.508 0.508)
			(layers "B.Cu" "B.Mask" "B.Paste")
			(net "SGPIO_BMC_DIN")
		)
		(zone
			(layer "B.Cu")
			(hatch none 0.5)
			(connect_pads
				(clearance 0)
			)
			(min_thickness 0.25)
			(keepout
				(tracks allowed)
				(vias not_allowed)
				(pads allowed)
				(copperpour not_allowed)
				(footprints allowed)
			)
			(placement
				(enabled no)
				(sheetname "")
			)
			(fill
				(thermal_gap 0.5)
				(thermal_bridge_width 0.5)
				(island_removal_mode 0)
			)
			(polygon
				(pts
					(xy 374.142 -66.675) (xy 373.634 -66.675) (xy 373.634 -66.294) (xy 374.142 -66.294)
				)
			)
		)
		(zone
			(layer "B.Cu")
			(hatch none 0.5)
			(connect_pads
				(clearance 0)
			)
			(min_thickness 0.25)
			(keepout
				(tracks not_allowed)
				(vias allowed)
				(pads allowed)
				(copperpour not_allowed)
				(footprints allowed)
			)
			(placement
				(enabled no)
				(sheetname "")
			)
			(fill
				(thermal_gap 0.5)
				(thermal_bridge_width 0.5)
				(island_removal_mode 0)
			)
			(polygon
				(pts
					(xy 374.142 -66.294) (xy 373.634 -66.294) (xy 373.634 -66.675) (xy 374.142 -66.675)
				)
			)
		)
	)
	(footprint ""
		(layer "B.Cu")
		(at 486.3338 -34.9504 90)
		(property "Reference" "R9W35"
			(at 0.8382 -0.67818 90)
			(unlocked yes)
			(layer "B.SilkS")
			(effects
				(font
					(size 0.4064 0.254)
					(thickness 0.1524)
				)
				(justify left mirror)
			)
		)
		(property "Value" ""
			(at 0 0 90)
			(layer "B.Fab")
			(effects
				(font
					(size 1.27 1.27)
				)
				(justify mirror)
			)
		)
		(duplicate_pad_numbers_are_jumpers no)
		(fp_poly
			(pts
				(xy 0.2794 -0.1016) (xy -0.2794 -0.1016) (xy -0.2794 0.9906) (xy 0.2794 0.9906)
			)
			(stroke
				(width 0)
				(type default)
			)
			(fill no)
			(layer "B.CrtYd")
		)
		(fp_line
			(start 0.2794 -0.1016)
			(end 0.2794 0.9906)
			(stroke
				(width 0.1)
				(type default)
			)
			(layer "B.Fab")
		)
		(fp_line
			(start -0.2794 -0.1016)
			(end 0.2794 -0.1016)
			(stroke
				(width 0.1)
				(type default)
			)
			(layer "B.Fab")
		)
		(fp_line
			(start 0.2794 0.9906)
			(end -0.2794 0.9906)
			(stroke
				(width 0.1)
				(type default)
			)
			(layer "B.Fab")
		)
		(fp_line
			(start -0.2794 0.9906)
			(end -0.2794 -0.1016)
			(stroke
				(width 0.1)
				(type default)
			)
			(layer "B.Fab")
		)
		(pad "1" smd rect
			(at 0 0 270)
			(size 0.508 0.508)
			(layers "B.Cu" "B.Mask" "B.Paste")
			(net "P3V3_STBY")
		)
		(pad "2" smd rect
			(at 0 0.889 270)
			(size 0.508 0.508)
			(layers "B.Cu" "B.Mask" "B.Paste")
			(net "SP2_BMC_CM_UART_RX_R")
		)
		(zone
			(layer "B.Cu")
			(hatch none 0.5)
			(connect_pads
				(clearance 0)
			)
			(min_thickness 0.25)
			(keepout
				(tracks allowed)
				(vias not_allowed)
				(pads allowed)
				(copperpour not_allowed)
				(footprints allowed)
			)
			(placement
				(enabled no)
				(sheetname "")
			)
			(fill
				(thermal_gap 0.5)
				(thermal_bridge_width 0.5)
				(island_removal_mode 0)
			)
			(polygon
				(pts
					(xy 486.5878 -35.2044) (xy 486.5878 -34.6964) (xy 486.9688 -34.6964) (xy 486.9688 -35.2044)
				)
			)
		)
		(zone
			(layer "B.Cu")
			(hatch none 0.5)
			(connect_pads
				(clearance 0)
			)
			(min_thickness 0.25)
			(keepout
				(tracks not_allowed)
				(vias allowed)
				(pads allowed)
				(copperpour not_allowed)
				(footprints allowed)
			)
			(placement
				(enabled no)
				(sheetname "")
			)
			(fill
				(thermal_gap 0.5)
				(thermal_bridge_width 0.5)
				(island_removal_mode 0)
			)
			(polygon
				(pts
					(xy 486.9688 -35.2044) (xy 486.9688 -34.6964) (xy 486.5878 -34.6964) (xy 486.5878 -35.2044)
				)
			)
		)
	)
	(footprint ""
		(layer "B.Cu")
		(at 499.521226 -34.715704 -90)
		(property "Reference" "R9F65"
			(at 0 0 90)
			(layer "B.SilkS")
			(hide yes)
			(effects
				(font
					(size 1.27 1.27)
				)
				(justify mirror)
			)
		)
		(property "Value" ""
			(at 0 0 90)
			(layer "B.Fab")
			(effects
				(font
					(size 1.27 1.27)
				)
				(justify mirror)
			)
		)
		(duplicate_pad_numbers_are_jumpers no)
		(fp_poly
			(pts
				(xy 0.2794 -0.1016) (xy -0.2794 -0.1016) (xy -0.2794 0.9906) (xy 0.2794 0.9906)
			)
			(stroke
				(width 0)
				(type default)
			)
			(fill no)
			(layer "B.CrtYd")
		)
		(fp_line
			(start -0.2794 0.9906)
			(end -0.2794 -0.1016)
			(stroke
				(width 0.1)
				(type default)
			)
			(layer "B.Fab")
		)
		(fp_line
			(start 0.2794 0.9906)
			(end -0.2794 0.9906)
			(stroke
				(width 0.1)
				(type default)
			)
			(layer "B.Fab")
		)
		(fp_line
			(start -0.2794 -0.1016)
			(end 0.2794 -0.1016)
			(stroke
				(width 0.1)
				(type default)
			)
			(layer "B.Fab")
		)
		(fp_line
			(start 0.2794 -0.1016)
			(end 0.2794 0.9906)
			(stroke
				(width 0.1)
				(type default)
			)
			(layer "B.Fab")
		)
		(pad "1" smd rect
			(at 0 0 90)
			(size 0.508 0.508)
			(layers "B.Cu" "B.Mask" "B.Paste")
			(net "SP2_BMC_CM_UART_TX_R1")
		)
		(pad "2" smd rect
			(at 0 0.889 90)
			(size 0.508 0.508)
			(layers "B.Cu" "B.Mask" "B.Paste")
			(net "SP2_BMC_CM_UART_TX_R")
		)
		(zone
			(layer "B.Cu")
			(hatch none 0.5)
			(connect_pads
				(clearance 0)
			)
			(min_thickness 0.25)
			(keepout
				(tracks not_allowed)
				(vias allowed)
				(pads allowed)
				(copperpour not_allowed)
				(footprints allowed)
			)
			(placement
				(enabled no)
				(sheetname "")
			)
			(fill
				(thermal_gap 0.5)
				(thermal_bridge_width 0.5)
				(island_removal_mode 0)
			)
			(polygon
				(pts
					(xy 498.886226 -34.461704) (xy 498.886226 -34.969704) (xy 499.267226 -34.969704) (xy 499.267226 -34.461704)
				)
			)
		)
		(zone
			(layer "B.Cu")
			(hatch none 0.5)
			(connect_pads
				(clearance 0)
			)
			(min_thickness 0.25)
			(keepout
				(tracks allowed)
				(vias not_allowed)
				(pads allowed)
				(copperpour not_allowed)
				(footprints allowed)
			)
			(placement
				(enabled no)
				(sheetname "")
			)
			(fill
				(thermal_gap 0.5)
				(thermal_bridge_width 0.5)
				(island_removal_mode 0)
			)
			(polygon
				(pts
					(xy 499.267226 -34.461704) (xy 499.267226 -34.969704) (xy 498.886226 -34.969704) (xy 498.886226 -34.461704)
				)
			)
		)
	)
	(footprint ""
		(layer "B.Cu")
		(at 180.653182 -20.014692 180)
		(property "Reference" "R6T8"
			(at 0 0 0)
			(layer "B.SilkS")
			(hide yes)
			(effects
				(font
					(size 1.27 1.27)
				)
				(justify mirror)
			)
		)
		(property "Value" ""
			(at 0 0 0)
			(layer "B.Fab")
			(effects
				(font
					(size 1.27 1.27)
				)
				(justify mirror)
			)
		)
		(duplicate_pad_numbers_are_jumpers no)
		(fp_rect
			(start -0.2794 -0.1016)
			(end 0.2794 0.9906)
			(stroke
				(width 0)
				(type default)
			)
			(fill no)
			(layer "B.CrtYd")
		)
		(fp_line
			(start 0.2794 0.9906)
			(end -0.2794 0.9906)
			(stroke
				(width 0.1)
				(type default)
			)
			(layer "B.Fab")
		)
		(fp_line
			(start 0.2794 -0.1016)
			(end 0.2794 0.9906)
			(stroke
				(width 0.1)
				(type default)
			)
			(layer "B.Fab")
		)
		(fp_line
			(start -0.2794 0.9906)
			(end -0.2794 -0.1016)
			(stroke
				(width 0.1)
				(type default)
			)
			(layer "B.Fab")
		)
		(fp_line
			(start -0.2794 -0.1016)
			(end 0.2794 -0.1016)
			(stroke
				(width 0.1)
				(type default)
			)
			(layer "B.Fab")
		)
		(pad "1" smd rect
			(at 0 0)
			(size 0.508 0.508)
			(layers "B.Cu" "B.Mask" "B.Paste")
			(net "PVCCIO_CPU0")
		)
		(pad "2" smd rect
			(at 0 0.889)
			(size 0.508 0.508)
			(layers "B.Cu" "B.Mask" "B.Paste")
			(net "XDP_CPU_OBSFN_B0_MBP6_N")
		)
		(zone
			(layer "B.Cu")
			(hatch none 0.5)
			(connect_pads
				(clearance 0)
			)
			(min_thickness 0.25)
			(keepout
				(tracks allowed)
				(vias not_allowed)
				(pads allowed)
				(copperpour not_allowed)
				(footprints allowed)
			)
			(placement
				(enabled no)
				(sheetname "")
			)
			(fill
				(thermal_gap 0.5)
				(thermal_bridge_width 0.5)
				(island_removal_mode 0)
			)
			(polygon
				(pts
					(xy 180.907182 -20.268692) (xy 180.907182 -20.649692) (xy 180.399182 -20.649692) (xy 180.399182 -20.268692)
				)
			)
		)
		(zone
			(layer "B.Cu")
			(hatch none 0.5)
			(connect_pads
				(clearance 0)
			)
			(min_thickness 0.25)
			(keepout
				(tracks not_allowed)
				(vias allowed)
				(pads allowed)
				(copperpour not_allowed)
				(footprints allowed)
			)
			(placement
				(enabled no)
				(sheetname "")
			)
			(fill
				(thermal_gap 0.5)
				(thermal_bridge_width 0.5)
				(island_removal_mode 0)
			)
			(polygon
				(pts
					(xy 180.907182 -20.268692) (xy 180.907182 -20.649692) (xy 180.399182 -20.649692) (xy 180.399182 -20.268692)
				)
			)
		)
	)
	(footprint ""
		(layer "B.Cu")
		(at 340.3092 -87.1982 180)
		(property "Reference" "R3P13"
			(at 0 0 0)
			(layer "B.SilkS")
			(hide yes)
			(effects
				(font
					(size 1.27 1.27)
				)
				(justify mirror)
			)
		)
		(property "Value" ""
			(at 0 0 0)
			(layer "B.Fab")
			(effects
				(font
					(size 1.27 1.27)
				)
				(justify mirror)
			)
		)
		(duplicate_pad_numbers_are_jumpers no)
		(fp_poly
			(pts
				(xy 0.2794 -0.1016) (xy -0.2794 -0.1016) (xy -0.2794 0.9906) (xy 0.2794 0.9906)
			)
			(stroke
				(width 0)
				(type default)
			)
			(fill no)
			(layer "B.CrtYd")
		)
		(fp_line
			(start 0.2794 0.9906)
			(end -0.2794 0.9906)
			(stroke
				(width 0.1)
				(type default)
			)
			(layer "B.Fab")
		)
		(fp_line
			(start 0.2794 -0.1016)
			(end 0.2794 0.9906)
			(stroke
				(width 0.1)
				(type default)
			)
			(layer "B.Fab")
		)
		(fp_line
			(start -0.2794 0.9906)
			(end -0.2794 -0.1016)
			(stroke
				(width 0.1)
				(type default)
			)
			(layer "B.Fab")
		)
		(fp_line
			(start -0.2794 -0.1016)
			(end 0.2794 -0.1016)
			(stroke
				(width 0.1)
				(type default)
			)
			(layer "B.Fab")
		)
		(pad "1" smd rect
			(at 0 0)
			(size 0.508 0.508)
			(layers "B.Cu" "B.Mask" "B.Paste")
			(net "PVCCIO_CPU0")
		)
		(pad "2" smd rect
			(at 0 0.889)
			(size 0.508 0.508)
			(layers "B.Cu" "B.Mask" "B.Paste")
			(net "SVID_DIO0_CPU0_R")
		)
		(zone
			(layer "B.Cu")
			(hatch none 0.5)
			(connect_pads
				(clearance 0)
			)
			(min_thickness 0.25)
			(keepout
				(tracks not_allowed)
				(vias allowed)
				(pads allowed)
				(copperpour not_allowed)
				(footprints allowed)
			)
			(placement
				(enabled no)
				(sheetname "")
			)
			(fill
				(thermal_gap 0.5)
				(thermal_bridge_width 0.5)
				(island_removal_mode 0)
			)
			(polygon
				(pts
					(xy 340.0552 -87.8332) (xy 340.5632 -87.8332) (xy 340.5632 -87.4522) (xy 340.0552 -87.4522)
				)
			)
		)
		(zone
			(layer "B.Cu")
			(hatch none 0.5)
			(connect_pads
				(clearance 0)
			)
			(min_thickness 0.25)
			(keepout
				(tracks allowed)
				(vias not_allowed)
				(pads allowed)
				(copperpour not_allowed)
				(footprints allowed)
			)
			(placement
				(enabled no)
				(sheetname "")
			)
			(fill
				(thermal_gap 0.5)
				(thermal_bridge_width 0.5)
				(island_removal_mode 0)
			)
			(polygon
				(pts
					(xy 340.0552 -87.4522) (xy 340.5632 -87.4522) (xy 340.5632 -87.8332) (xy 340.0552 -87.8332)
				)
			)
		)
	)
	(footprint ""
		(layer "B.Cu")
		(at 23.876 -77.089 180)
		(property "Reference" "R9P21"
			(at 0 0 0)
			(layer "B.SilkS")
			(hide yes)
			(effects
				(font
					(size 1.27 1.27)
				)
				(justify mirror)
			)
		)
		(property "Value" ""
			(at 0 0 0)
			(layer "B.Fab")
			(effects
				(font
					(size 1.27 1.27)
				)
				(justify mirror)
			)
		)
		(duplicate_pad_numbers_are_jumpers no)
		(fp_poly
			(pts
				(xy 0.2794 -0.1016) (xy -0.2794 -0.1016) (xy -0.2794 0.9906) (xy 0.2794 0.9906)
			)
			(stroke
				(width 0)
				(type default)
			)
			(fill no)
			(layer "B.CrtYd")
		)
		(fp_line
			(start 0.2794 0.9906)
			(end -0.2794 0.9906)
			(stroke
				(width 0.1)
				(type default)
			)
			(layer "B.Fab")
		)
		(fp_line
			(start 0.2794 -0.1016)
			(end 0.2794 0.9906)
			(stroke
				(width 0.1)
				(type default)
			)
			(layer "B.Fab")
		)
		(fp_line
			(start -0.2794 0.9906)
			(end -0.2794 -0.1016)
			(stroke
				(width 0.1)
				(type default)
			)
			(layer "B.Fab")
		)
		(fp_line
			(start -0.2794 -0.1016)
			(end 0.2794 -0.1016)
			(stroke
				(width 0.1)
				(type default)
			)
			(layer "B.Fab")
		)
		(pad "1" smd rect
			(at 0 0)
			(size 0.508 0.508)
			(layers "B.Cu" "B.Mask" "B.Paste")
			(net "A_HSC_TIMER")
		)
		(pad "2" smd rect
			(at 0 0.889)
			(size 0.508 0.508)
			(layers "B.Cu" "B.Mask" "B.Paste")
			(net "A_HSC_TIMER_R")
		)
		(zone
			(layer "B.Cu")
			(hatch none 0.5)
			(connect_pads
				(clearance 0)
			)
			(min_thickness 0.25)
			(keepout
				(tracks not_allowed)
				(vias allowed)
				(pads allowed)
				(copperpour not_allowed)
				(footprints allowed)
			)
			(placement
				(enabled no)
				(sheetname "")
			)
			(fill
				(thermal_gap 0.5)
				(thermal_bridge_width 0.5)
				(island_removal_mode 0)
			)
			(polygon
				(pts
					(xy 23.622 -77.724) (xy 24.13 -77.724) (xy 24.13 -77.343) (xy 23.622 -77.343)
				)
			)
		)
		(zone
			(layer "B.Cu")
			(hatch none 0.5)
			(connect_pads
				(clearance 0)
			)
			(min_thickness 0.25)
			(keepout
				(tracks allowed)
				(vias not_allowed)
				(pads allowed)
				(copperpour not_allowed)
				(footprints allowed)
			)
			(placement
				(enabled no)
				(sheetname "")
			)
			(fill
				(thermal_gap 0.5)
				(thermal_bridge_width 0.5)
				(island_removal_mode 0)
			)
			(polygon
				(pts
					(xy 23.622 -77.343) (xy 24.13 -77.343) (xy 24.13 -77.724) (xy 23.622 -77.724)
				)
			)
		)
	)
	(footprint ""
		(layer "B.Cu")
		(at 102.692454 -77.82814)
		(property "Reference" "C8P16"
			(at 0 0 0)
			(layer "B.SilkS")
			(hide yes)
			(effects
				(font
					(size 1.27 1.27)
				)
				(justify mirror)
			)
		)
		(property "Value" ""
			(at 0 0 0)
			(layer "B.Fab")
			(effects
				(font
					(size 1.27 1.27)
				)
				(justify mirror)
			)
		)
		(duplicate_pad_numbers_are_jumpers no)
		(fp_poly
			(pts
				(xy 0.7239 -0.2159) (xy -0.7239 -0.2159) (xy -0.7239 1.9939) (xy 0.7239 1.9939)
			)
			(stroke
				(width 0)
				(type default)
			)
			(fill no)
			(layer "B.CrtYd")
		)
		(fp_line
			(start -0.7239 -0.2159)
			(end 0.7239 -0.2159)
			(stroke
				(width 0.1)
				(type default)
			)
			(layer "B.Fab")
		)
		(fp_line
			(start -0.7239 1.9939)
			(end -0.7239 -0.2159)
			(stroke
				(width 0.1)
				(type default)
			)
			(layer "B.Fab")
		)
		(fp_line
			(start 0.7239 -0.2159)
			(end 0.7239 1.9939)
			(stroke
				(width 0.1)
				(type default)
			)
			(layer "B.Fab")
		)
		(fp_line
			(start 0.7239 1.9939)
			(end -0.7239 1.9939)
			(stroke
				(width 0.1)
				(type default)
			)
			(layer "B.Fab")
		)
		(pad "1" smd rect
			(at 0 0 180)
			(size 1.27 1.016)
			(layers "B.Cu" "B.Mask" "B.Paste")
			(net "PVCCIN_CPU1")
		)
		(pad "2" smd rect
			(at 0 1.778 180)
			(size 1.27 1.016)
			(layers "B.Cu" "B.Mask" "B.Paste")
			(net "GND")
		)
		(zone
			(layer "B.Cu")
			(hatch none 0.5)
			(connect_pads
				(clearance 0)
			)
			(min_thickness 0.25)
			(keepout
				(tracks not_allowed)
				(vias allowed)
				(pads allowed)
				(copperpour not_allowed)
				(footprints allowed)
			)
			(placement
				(enabled no)
				(sheetname "")
			)
			(fill
				(thermal_gap 0.5)
				(thermal_bridge_width 0.5)
				(island_removal_mode 0)
			)
			(polygon
				(pts
					(xy 103.327454 -77.32014) (xy 102.057454 -77.32014) (xy 102.057454 -76.55814) (xy 103.327454 -76.55814)
				)
			)
		)
	)
)
